(kicad_pcb
	(version 20260206)
	(generator "pcbnew")
	(generator_version "10.0")
	(general
		(thickness 1.6)
		(legacy_teardrops no)
	)
	(paper "A4")
	(title_block
		(title "03242023_DA0F0TMBIJ0_F0T_Motherboard_J_brd_V01_OCP.brd")
		(comment 1 "Grand Teton / footprints 2184-2187 of 6105")
	)
	(layers
		(0 "F.Cu" signal "TOP")
		(4 "In1.Cu" signal "GND")
		(6 "In2.Cu" signal "IN1")
		(8 "In3.Cu" signal "GND1")
		(10 "In4.Cu" signal "IN2")
		(12 "In5.Cu" signal "GND2")
		(14 "In6.Cu" signal "IN3")
		(16 "In7.Cu" signal "GND3")
		(18 "In8.Cu" signal "VCC")
		(20 "In9.Cu" signal "VCC1")
		(22 "In10.Cu" signal "GND4")
		(24 "In11.Cu" signal "IN4")
		(26 "In12.Cu" signal "GND5")
		(28 "In13.Cu" signal "IN5")
		(30 "In14.Cu" signal "GND6")
		(32 "In15.Cu" signal "IN6")
		(34 "In16.Cu" signal "GND7")
		(2 "B.Cu" signal "BOTTOM")
		(9 "F.Adhes" user "F.Adhesive")
		(11 "B.Adhes" user "B.Adhesive")
		(13 "F.Paste" user "Package Geometry/Pastemask Top")
		(15 "B.Paste" user "Package Geometry/Pastemask Bottom")
		(5 "F.SilkS" user "Ref Des/Silkscreen Top")
		(7 "B.SilkS" user "Ref Des/Silkscreen Bottom")
		(1 "F.Mask" user "Board Geometry/Soldermask Top")
		(3 "B.Mask" user "Board Geometry/Soldermask Bottom")
		(17 "Dwgs.User" user "User.Drawings")
		(19 "Cmts.User" user "User.Comments")
		(21 "Eco1.User" user "User.Eco1")
		(23 "Eco2.User" user "User.Eco2")
		(25 "Edge.Cuts" user "Board Geometry/Outline")
		(27 "Margin" user)
		(31 "F.CrtYd" user "Package Geometry/Place Bound Top")
		(29 "B.CrtYd" user "Package Geometry/Place Bound Bottom")
		(35 "F.Fab" user "Ref Des/Assembly Top")
		(33 "B.Fab" user "Ref Des/Assembly Bottom")
	)
	(footprint ""
		(layer "F.Cu")
		(at 429.28032 -140.654278 -90)
		(property "Reference" "PR120"
			(at 0 0 270)
			(layer "F.SilkS")
			(hide yes)
			(effects
				(font
					(size 1.27 1.27)
				)
			)
		)
		(property "Value" ""
			(at 0 0 270)
			(layer "F.Fab")
			(effects
				(font
					(size 1.27 1.27)
				)
			)
		)
		(duplicate_pad_numbers_are_jumpers no)
		(fp_line
			(start -0.7874 0.4064)
			(end -0.7874 -0.4064)
			(stroke
				(width 0.1524)
				(type default)
			)
			(layer "F.SilkS")
		)
		(fp_line
			(start 0.7874 0.4064)
			(end -0.7874 0.4064)
			(stroke
				(width 0.1524)
				(type default)
			)
			(layer "F.SilkS")
		)
		(fp_line
			(start -0.7874 -0.4064)
			(end 0.7874 -0.4064)
			(stroke
				(width 0.1524)
				(type default)
			)
			(layer "F.SilkS")
		)
		(fp_line
			(start 0.7874 -0.4064)
			(end 0.7874 0.4064)
			(stroke
				(width 0.1524)
				(type default)
			)
			(layer "F.SilkS")
		)
		(fp_line
			(start -0.67945 0.3048)
			(end -0.67945 -0.305054)
			(stroke
				(width 0.1)
				(type default)
			)
			(layer "F.Fab")
		)
		(fp_line
			(start -0.12065 0.3048)
			(end -0.67945 0.3048)
			(stroke
				(width 0.1)
				(type default)
			)
			(layer "F.Fab")
		)
		(fp_line
			(start 0.120396 0.3048)
			(end 0.120396 0.2794)
			(stroke
				(width 0.1)
				(type default)
			)
			(layer "F.Fab")
		)
		(fp_line
			(start 0.67945 0.3048)
			(end 0.120396 0.3048)
			(stroke
				(width 0.1)
				(type default)
			)
			(layer "F.Fab")
		)
		(fp_line
			(start -0.12065 0.2794)
			(end -0.12065 0.3048)
			(stroke
				(width 0.1)
				(type default)
			)
			(layer "F.Fab")
		)
		(fp_line
			(start 0.120396 0.2794)
			(end -0.12065 0.2794)
			(stroke
				(width 0.1)
				(type default)
			)
			(layer "F.Fab")
		)
		(fp_line
			(start -0.12065 -0.2794)
			(end 0.12065 -0.2794)
			(stroke
				(width 0.1)
				(type default)
			)
			(layer "F.Fab")
		)
		(fp_line
			(start 0.12065 -0.2794)
			(end 0.12065 -0.3048)
			(stroke
				(width 0.1)
				(type default)
			)
			(layer "F.Fab")
		)
		(fp_line
			(start 0.12065 -0.3048)
			(end 0.67945 -0.3048)
			(stroke
				(width 0.1)
				(type default)
			)
			(layer "F.Fab")
		)
		(fp_line
			(start 0.67945 -0.3048)
			(end 0.67945 0.3048)
			(stroke
				(width 0.1)
				(type default)
			)
			(layer "F.Fab")
		)
		(fp_line
			(start -0.67945 -0.305054)
			(end -0.12065 -0.305054)
			(stroke
				(width 0.1)
				(type default)
			)
			(layer "F.Fab")
		)
		(fp_line
			(start -0.12065 -0.305054)
			(end -0.12065 -0.2794)
			(stroke
				(width 0.1)
				(type default)
			)
			(layer "F.Fab")
		)
		(pad "1" smd circle
			(at -0.40005 0 270)
			(size 0 0)
			(layers "F.Cu" "F.Mask" "F.Paste")
			(net "SH_PVCCINFAON_CPU0")
		)
		(pad "2" smd circle
			(at 0.40005 0 270)
			(size 0 0)
			(layers "F.Cu" "F.Mask" "F.Paste")
			(net "SH_PVCCINFAON_CPU0_R")
		)
	)
	(footprint ""
		(layer "F.Cu")
		(at 136.668256 -68.445888 180)
		(property "Reference" "R2304"
			(at 0 0 180)
			(layer "F.SilkS")
			(hide yes)
			(effects
				(font
					(size 1.27 1.27)
				)
			)
		)
		(property "Value" ""
			(at 0 0 180)
			(layer "F.Fab")
			(effects
				(font
					(size 1.27 1.27)
				)
			)
		)
		(duplicate_pad_numbers_are_jumpers no)
		(fp_line
			(start 0.7874 0.4064)
			(end -0.7874 0.4064)
			(stroke
				(width 0.1524)
				(type default)
			)
			(layer "F.SilkS")
		)
		(fp_line
			(start 0.7874 -0.4064)
			(end 0.7874 0.4064)
			(stroke
				(width 0.1524)
				(type default)
			)
			(layer "F.SilkS")
		)
		(fp_line
			(start -0.7874 0.4064)
			(end -0.7874 -0.4064)
			(stroke
				(width 0.1524)
				(type default)
			)
			(layer "F.SilkS")
		)
		(fp_line
			(start -0.7874 -0.4064)
			(end 0.7874 -0.4064)
			(stroke
				(width 0.1524)
				(type default)
			)
			(layer "F.SilkS")
		)
		(fp_line
			(start 0.67945 0.3048)
			(end 0.120396 0.3048)
			(stroke
				(width 0.1)
				(type default)
			)
			(layer "F.Fab")
		)
		(fp_line
			(start 0.67945 -0.3048)
			(end 0.67945 0.3048)
			(stroke
				(width 0.1)
				(type default)
			)
			(layer "F.Fab")
		)
		(fp_line
			(start 0.12065 -0.2794)
			(end 0.12065 -0.3048)
			(stroke
				(width 0.1)
				(type default)
			)
			(layer "F.Fab")
		)
		(fp_line
			(start 0.12065 -0.3048)
			(end 0.67945 -0.3048)
			(stroke
				(width 0.1)
				(type default)
			)
			(layer "F.Fab")
		)
		(fp_line
			(start 0.120396 0.3048)
			(end 0.120396 0.2794)
			(stroke
				(width 0.1)
				(type default)
			)
			(layer "F.Fab")
		)
		(fp_line
			(start 0.120396 0.2794)
			(end -0.12065 0.2794)
			(stroke
				(width 0.1)
				(type default)
			)
			(layer "F.Fab")
		)
		(fp_line
			(start -0.12065 0.3048)
			(end -0.67945 0.3048)
			(stroke
				(width 0.1)
				(type default)
			)
			(layer "F.Fab")
		)
		(fp_line
			(start -0.12065 0.2794)
			(end -0.12065 0.3048)
			(stroke
				(width 0.1)
				(type default)
			)
			(layer "F.Fab")
		)
		(fp_line
			(start -0.12065 -0.2794)
			(end 0.12065 -0.2794)
			(stroke
				(width 0.1)
				(type default)
			)
			(layer "F.Fab")
		)
		(fp_line
			(start -0.12065 -0.305054)
			(end -0.12065 -0.2794)
			(stroke
				(width 0.1)
				(type default)
			)
			(layer "F.Fab")
		)
		(fp_line
			(start -0.67945 0.3048)
			(end -0.67945 -0.305054)
			(stroke
				(width 0.1)
				(type default)
			)
			(layer "F.Fab")
		)
		(fp_line
			(start -0.67945 -0.305054)
			(end -0.12065 -0.305054)
			(stroke
				(width 0.1)
				(type default)
			)
			(layer "F.Fab")
		)
		(pad "1" smd circle
			(at -0.40005 0 180)
			(size 0 0)
			(layers "F.Cu" "F.Mask" "F.Paste")
			(net "P3V3_AUX")
		)
		(pad "2" smd circle
			(at 0.40005 0 180)
			(size 0 0)
			(layers "F.Cu" "F.Mask" "F.Paste")
			(net "E1S_0_PRSNT_N")
		)
	)
	(footprint ""
		(layer "F.Cu")
		(at 369.191286 -357.11638 90)
		(property "Reference" "PC1253"
			(at 0 0 90)
			(layer "F.SilkS")
			(hide yes)
			(effects
				(font
					(size 1.27 1.27)
				)
			)
		)
		(property "Value" ""
			(at 0 0 90)
			(layer "F.Fab")
			(effects
				(font
					(size 1.27 1.27)
				)
			)
		)
		(duplicate_pad_numbers_are_jumpers no)
		(fp_line
			(start 0.7874 -0.4064)
			(end 0.7874 0.4064)
			(stroke
				(width 0.1524)
				(type default)
			)
			(layer "F.SilkS")
		)
		(fp_line
			(start -0.7874 -0.4064)
			(end 0.7874 -0.4064)
			(stroke
				(width 0.1524)
				(type default)
			)
			(layer "F.SilkS")
		)
		(fp_line
			(start 0.7874 0.4064)
			(end -0.7874 0.4064)
			(stroke
				(width 0.1524)
				(type default)
			)
			(layer "F.SilkS")
		)
		(fp_line
			(start -0.7874 0.4064)
			(end -0.7874 -0.4064)
			(stroke
				(width 0.1524)
				(type default)
			)
			(layer "F.SilkS")
		)
		(fp_line
			(start -0.12065 -0.305054)
			(end -0.12065 -0.2794)
			(stroke
				(width 0.1)
				(type default)
			)
			(layer "F.Fab")
		)
		(fp_line
			(start -0.67945 -0.305054)
			(end -0.12065 -0.305054)
			(stroke
				(width 0.1)
				(type default)
			)
			(layer "F.Fab")
		)
		(fp_line
			(start 0.67945 -0.3048)
			(end 0.67945 0.3048)
			(stroke
				(width 0.1)
				(type default)
			)
			(layer "F.Fab")
		)
		(fp_line
			(start 0.12065 -0.3048)
			(end 0.67945 -0.3048)
			(stroke
				(width 0.1)
				(type default)
			)
			(layer "F.Fab")
		)
		(fp_line
			(start 0.12065 -0.2794)
			(end 0.12065 -0.3048)
			(stroke
				(width 0.1)
				(type default)
			)
			(layer "F.Fab")
		)
		(fp_line
			(start -0.12065 -0.2794)
			(end 0.12065 -0.2794)
			(stroke
				(width 0.1)
				(type default)
			)
			(layer "F.Fab")
		)
		(fp_line
			(start 0.120396 0.2794)
			(end -0.12065 0.2794)
			(stroke
				(width 0.1)
				(type default)
			)
			(layer "F.Fab")
		)
		(fp_line
			(start -0.12065 0.2794)
			(end -0.12065 0.3048)
			(stroke
				(width 0.1)
				(type default)
			)
			(layer "F.Fab")
		)
		(fp_line
			(start 0.67945 0.3048)
			(end 0.120396 0.3048)
			(stroke
				(width 0.1)
				(type default)
			)
			(layer "F.Fab")
		)
		(fp_line
			(start 0.120396 0.3048)
			(end 0.120396 0.2794)
			(stroke
				(width 0.1)
				(type default)
			)
			(layer "F.Fab")
		)
		(fp_line
			(start -0.12065 0.3048)
			(end -0.67945 0.3048)
			(stroke
				(width 0.1)
				(type default)
			)
			(layer "F.Fab")
		)
		(fp_line
			(start -0.67945 0.3048)
			(end -0.67945 -0.305054)
			(stroke
				(width 0.1)
				(type default)
			)
			(layer "F.Fab")
		)
		(pad "1" smd circle
			(at -0.40005 0 90)
			(size 0 0)
			(layers "F.Cu" "F.Mask" "F.Paste")
			(net "PVPP_HBM_CPU0_FB")
		)
		(pad "2" smd circle
			(at 0.40005 0 90)
			(size 0 0)
			(layers "F.Cu" "F.Mask" "F.Paste")
			(net "SH_PVPP_HBM_CPU0_P")
		)
	)
	(footprint ""
		(layer "F.Cu")
		(at 108.727494 -333.804514 -90)
		(property "Reference" "PC562_P1_2"
			(at 0 0 270)
			(layer "F.SilkS")
			(hide yes)
			(effects
				(font
					(size 1.27 1.27)
				)
			)
		)
		(property "Value" ""
			(at 0 0 270)
			(layer "F.Fab")
			(effects
				(font
					(size 1.27 1.27)
				)
			)
		)
		(duplicate_pad_numbers_are_jumpers no)
		(fp_line
			(start -0.7874 0.4064)
			(end -0.7874 -0.4064)
			(stroke
				(width 0.1524)
				(type default)
			)
			(layer "F.SilkS")
		)
		(fp_line
			(start 0.7874 0.4064)
			(end -0.7874 0.4064)
			(stroke
				(width 0.1524)
				(type default)
			)
			(layer "F.SilkS")
		)
		(fp_line
			(start -0.7874 -0.4064)
			(end 0.7874 -0.4064)
			(stroke
				(width 0.1524)
				(type default)
			)
			(layer "F.SilkS")
		)
		(fp_line
			(start 0.7874 -0.4064)
			(end 0.7874 0.4064)
			(stroke
				(width 0.1524)
				(type default)
			)
			(layer "F.SilkS")
		)
		(fp_line
			(start -0.67945 0.3048)
			(end -0.67945 -0.305054)
			(stroke
				(width 0.1)
				(type default)
			)
			(layer "F.Fab")
		)
		(fp_line
			(start -0.12065 0.3048)
			(end -0.67945 0.3048)
			(stroke
				(width 0.1)
				(type default)
			)
			(layer "F.Fab")
		)
		(fp_line
			(start 0.120396 0.3048)
			(end 0.120396 0.2794)
			(stroke
				(width 0.1)
				(type default)
			)
			(layer "F.Fab")
		)
		(fp_line
			(start 0.67945 0.3048)
			(end 0.120396 0.3048)
			(stroke
				(width 0.1)
				(type default)
			)
			(layer "F.Fab")
		)
		(fp_line
			(start -0.12065 0.2794)
			(end -0.12065 0.3048)
			(stroke
				(width 0.1)
				(type default)
			)
			(layer "F.Fab")
		)
		(fp_line
			(start 0.120396 0.2794)
			(end -0.12065 0.2794)
			(stroke
				(width 0.1)
				(type default)
			)
			(layer "F.Fab")
		)
		(fp_line
			(start -0.12065 -0.2794)
			(end 0.12065 -0.2794)
			(stroke
				(width 0.1)
				(type default)
			)
			(layer "F.Fab")
		)
		(fp_line
			(start 0.12065 -0.2794)
			(end 0.12065 -0.3048)
			(stroke
				(width 0.1)
				(type default)
			)
			(layer "F.Fab")
		)
		(fp_line
			(start 0.12065 -0.3048)
			(end 0.67945 -0.3048)
			(stroke
				(width 0.1)
				(type default)
			)
			(layer "F.Fab")
		)
		(fp_line
			(start 0.67945 -0.3048)
			(end 0.67945 0.3048)
			(stroke
				(width 0.1)
				(type default)
			)
			(layer "F.Fab")
		)
		(fp_line
			(start -0.67945 -0.305054)
			(end -0.12065 -0.305054)
			(stroke
				(width 0.1)
				(type default)
			)
			(layer "F.Fab")
		)
		(fp_line
			(start -0.12065 -0.305054)
			(end -0.12065 -0.2794)
			(stroke
				(width 0.1)
				(type default)
			)
			(layer "F.Fab")
		)
		(pad "1" smd circle
			(at -0.40005 0 270)
			(size 0 0)
			(layers "F.Cu" "F.Mask" "F.Paste")
			(net "SW_P12V_PVCCIN_CPU1_FLT")
		)
		(pad "2" smd circle
			(at 0.40005 0 270)
			(size 0 0)
			(layers "F.Cu" "F.Mask" "F.Paste")
			(net "GND")
		)
	)
)
